(kicad_pcb
	(version 20260206)
	(generator "pcbnew")
	(generator_version "10.0")
	(general
		(thickness 1.6)
		(legacy_teardrops no)
	)
	(paper "A4")
	(title_block
		(title "timecard-production-celestica-r4006 — R4006-B0001-02_R01.brd")
		(comment 1 "Time Appliance Project (Time Card) / footprints 971-975 of 1113")
	)
	(layers
		(0 "F.Cu" signal "TOP")
		(4 "In1.Cu" signal "L02_GND1")
		(6 "In2.Cu" signal "L03_SIG1")
		(8 "In3.Cu" signal "L04_GND2")
		(10 "In4.Cu" signal "L05_VCC1")
		(12 "In5.Cu" signal "L06_VCC2")
		(14 "In6.Cu" signal "L07_GND3")
		(16 "In7.Cu" signal "L08_SIG2")
		(18 "In8.Cu" signal "L09_GND4")
		(2 "B.Cu" signal "BOTTOM")
		(9 "F.Adhes" user "F.Adhesive")
		(11 "B.Adhes" user "B.Adhesive")
		(13 "F.Paste" user "Package Geometry/Pastemask Top")
		(15 "B.Paste" user "Package Geometry/Pastemask Bottom")
		(5 "F.SilkS" user "Ref Des/Silkscreen Top")
		(7 "B.SilkS" user "Ref Des/Silkscreen Bottom")
		(1 "F.Mask" user "Board Geometry/Soldermask Top")
		(3 "B.Mask" user "Board Geometry/Soldermask Bottom")
		(17 "Dwgs.User" user "User.Drawings")
		(19 "Cmts.User" user "User.Comments")
		(21 "Eco1.User" user "User.Eco1")
		(23 "Eco2.User" user "User.Eco2")
		(25 "Edge.Cuts" user "Board Geometry/Outline")
		(27 "Margin" user)
		(31 "F.CrtYd" user "Package Geometry/Place Bound Top")
		(29 "B.CrtYd" user "Package Geometry/Place Bound Bottom")
		(35 "F.Fab" user "Ref Des/Assembly Top")
		(33 "B.Fab" user "Ref Des/Assembly Bottom")
	)
	(footprint ""
		(layer "B.Cu")
		(at 88.519 -82.169 180)
		(property "Reference" "R206"
			(at -0.254 5.67563 0)
			(unlocked yes)
			(layer "B.SilkS")
			(effects
				(font
					(size 0.7874 0.5842)
					(thickness 0.1524)
				)
				(justify mirror)
			)
		)
		(property "Value" "VAL*"
			(at -0.02032 2.13233 180)
			(unlocked yes)
			(layer "B.Fab")
			(hide yes)
			(effects
				(font
					(size 0.7874 0.5842)
					(thickness 0.1524)
				)
				(justify mirror)
			)
		)
		(property "Device Type" "RESISTOR-G155-133R0-01,33OHM,1%"
			(at -0.008382 1.210564 180)
			(unlocked yes)
			(layer "B.Fab")
			(hide yes)
			(effects
				(font
					(size 0.7874 0.5842)
					(thickness 0.1524)
				)
				(justify mirror)
			)
		)
		(property "User Part Number" "PARTNUM*"
			(at -0.02032 4.024884 180)
			(unlocked yes)
			(layer "Cmts.User")
			(hide yes)
			(effects
				(font
					(size 0.7874 0.5842)
					(thickness 0.1524)
				)
				(justify mirror)
			)
		)
		(property "Tolerance" "TOL*"
			(at -0.044704 3.05435 180)
			(unlocked yes)
			(layer "Cmts.User")
			(hide yes)
			(effects
				(font
					(size 0.7874 0.5842)
					(thickness 0.1524)
				)
				(justify mirror)
			)
		)
		(duplicate_pad_numbers_are_jumpers no)
		(fp_line
			(start 1.143 0.5588)
			(end -1.143 0.5588)
			(stroke
				(width 0.1)
				(type default)
			)
			(layer "B.SilkS")
		)
		(fp_line
			(start 1.143 -0.5588)
			(end 1.143 0.5588)
			(stroke
				(width 0.1)
				(type default)
			)
			(layer "B.SilkS")
		)
		(fp_line
			(start -1.143 0.5588)
			(end -1.143 -0.5588)
			(stroke
				(width 0.1)
				(type default)
			)
			(layer "B.SilkS")
		)
		(fp_line
			(start -1.143 -0.5588)
			(end 1.143 -0.5588)
			(stroke
				(width 0.1)
				(type default)
			)
			(layer "B.SilkS")
		)
		(fp_rect
			(start 1.143 -0.5588)
			(end -1.143 0.5588)
			(stroke
				(width 0)
				(type default)
			)
			(fill no)
			(layer "B.CrtYd")
		)
		(fp_line
			(start 0.508 0.3048)
			(end -0.508 0.3048)
			(stroke
				(width 0.1)
				(type default)
			)
			(layer "B.Fab")
		)
		(fp_line
			(start 0.508 -0.3048)
			(end 0.508 0.3048)
			(stroke
				(width 0.1)
				(type default)
			)
			(layer "B.Fab")
		)
		(fp_line
			(start -0.508 0.3048)
			(end -0.508 -0.3048)
			(stroke
				(width 0.1)
				(type default)
			)
			(layer "B.Fab")
		)
		(fp_line
			(start -0.508 -0.3048)
			(end 0.508 -0.3048)
			(stroke
				(width 0.1)
				(type default)
			)
			(layer "B.Fab")
		)
		(pad "1" smd rect
			(at 0.5334 0)
			(size 0.7112 0.6096)
			(layers "B.Cu" "B.Mask" "B.Paste")
			(net "UNNAMED_127_MT25QL128ABA1ESES_2")
		)
		(pad "2" smd rect
			(at -0.5334 0)
			(size 0.7112 0.6096)
			(layers "B.Cu" "B.Mask" "B.Paste")
			(net "FLASH_DQ3")
		)
		(zone
			(layer "B.Cu")
			(hatch none 0.5)
			(connect_pads
				(clearance 0)
			)
			(min_thickness 0.25)
			(keepout
				(tracks allowed)
				(vias not_allowed)
				(pads allowed)
				(copperpour not_allowed)
				(footprints allowed)
			)
			(placement
				(enabled no)
				(sheetname "")
			)
			(fill
				(thermal_gap 0.5)
				(thermal_bridge_width 0.5)
				(island_removal_mode 0)
			)
			(polygon
				(pts
					(xy 88.4428 -81.8642) (xy 88.5952 -81.8642) (xy 88.5952 -82.4738) (xy 88.4428 -82.4738)
				)
			)
		)
	)
	(footprint ""
		(layer "B.Cu")
		(at 106.9086 -64.2874 90)
		(property "Reference" "R326"
			(at 3.5306 -0.14097 270)
			(unlocked yes)
			(layer "B.SilkS")
			(effects
				(font
					(size 0.7874 0.5842)
					(thickness 0.1524)
				)
				(justify mirror)
			)
		)
		(property "Value" "VAL*"
			(at -0.02032 2.13233 90)
			(unlocked yes)
			(layer "B.Fab")
			(hide yes)
			(effects
				(font
					(size 0.7874 0.5842)
					(thickness 0.1524)
				)
				(justify mirror)
			)
		)
		(property "Tolerance" "TOL*"
			(at -0.044704 3.05435 90)
			(unlocked yes)
			(layer "Cmts.User")
			(hide yes)
			(effects
				(font
					(size 0.7874 0.5842)
					(thickness 0.1524)
				)
				(justify mirror)
			)
		)
		(property "User Part Number" "PARTNUM*"
			(at -0.02032 4.024884 90)
			(unlocked yes)
			(layer "Cmts.User")
			(hide yes)
			(effects
				(font
					(size 0.7874 0.5842)
					(thickness 0.1524)
				)
				(justify mirror)
			)
		)
		(property "Device Type" "RESISTOR-G155-14701-01,4.7KOHMA"
			(at -0.008382 1.210564 90)
			(unlocked yes)
			(layer "B.Fab")
			(hide yes)
			(effects
				(font
					(size 0.7874 0.5842)
					(thickness 0.1524)
				)
				(justify mirror)
			)
		)
		(duplicate_pad_numbers_are_jumpers no)
		(fp_line
			(start 1.143 -0.5588)
			(end 1.143 0.5588)
			(stroke
				(width 0.1)
				(type default)
			)
			(layer "B.SilkS")
		)
		(fp_line
			(start -1.143 -0.5588)
			(end 1.143 -0.5588)
			(stroke
				(width 0.1)
				(type default)
			)
			(layer "B.SilkS")
		)
		(fp_line
			(start 1.143 0.5588)
			(end -1.143 0.5588)
			(stroke
				(width 0.1)
				(type default)
			)
			(layer "B.SilkS")
		)
		(fp_line
			(start -1.143 0.5588)
			(end -1.143 -0.5588)
			(stroke
				(width 0.1)
				(type default)
			)
			(layer "B.SilkS")
		)
		(fp_poly
			(pts
				(xy 1.143 0.5588) (xy -1.143 0.5588) (xy -1.143 -0.5588) (xy 1.143 -0.5588)
			)
			(stroke
				(width 0)
				(type default)
			)
			(fill no)
			(layer "B.CrtYd")
		)
		(fp_line
			(start 0.508 -0.3048)
			(end 0.508 0.3048)
			(stroke
				(width 0.1)
				(type default)
			)
			(layer "B.Fab")
		)
		(fp_line
			(start -0.508 -0.3048)
			(end 0.508 -0.3048)
			(stroke
				(width 0.1)
				(type default)
			)
			(layer "B.Fab")
		)
		(fp_line
			(start 0.508 0.3048)
			(end -0.508 0.3048)
			(stroke
				(width 0.1)
				(type default)
			)
			(layer "B.Fab")
		)
		(fp_line
			(start -0.508 0.3048)
			(end -0.508 -0.3048)
			(stroke
				(width 0.1)
				(type default)
			)
			(layer "B.Fab")
		)
		(pad "1" smd rect
			(at 0.5334 0 270)
			(size 0.7112 0.6096)
			(layers "B.Cu" "B.Mask" "B.Paste")
			(net "SG")
		)
		(pad "2" smd rect
			(at -0.5334 0 270)
			(size 0.7112 0.6096)
			(layers "B.Cu" "B.Mask" "B.Paste")
			(net "FPGA_IO_6")
		)
		(zone
			(layer "B.Cu")
			(hatch none 0.5)
			(connect_pads
				(clearance 0)
			)
			(min_thickness 0.25)
			(keepout
				(tracks not_allowed)
				(vias allowed)
				(pads allowed)
				(copperpour not_allowed)
				(footprints allowed)
			)
			(placement
				(enabled no)
				(sheetname "")
			)
			(fill
				(thermal_gap 0.5)
				(thermal_bridge_width 0.5)
				(island_removal_mode 0)
			)
			(polygon
				(pts
					(xy 107.2134 -64.3636) (xy 106.6038 -64.3636) (xy 106.6038 -64.2112) (xy 107.2134 -64.2112)
				)
			)
		)
		(zone
			(layer "B.Cu")
			(hatch none 0.5)
			(connect_pads
				(clearance 0)
			)
			(min_thickness 0.25)
			(keepout
				(tracks allowed)
				(vias not_allowed)
				(pads allowed)
				(copperpour not_allowed)
				(footprints allowed)
			)
			(placement
				(enabled no)
				(sheetname "")
			)
			(fill
				(thermal_gap 0.5)
				(thermal_bridge_width 0.5)
				(island_removal_mode 0)
			)
			(polygon
				(pts
					(xy 107.2134 -64.3636) (xy 106.6038 -64.3636) (xy 106.6038 -64.2112) (xy 107.2134 -64.2112)
				)
			)
		)
	)
	(footprint ""
		(layer "B.Cu")
		(at 160.02 -50.513996 90)
		(property "Reference" "R101"
			(at -7.874 1.35763 270)
			(unlocked yes)
			(layer "B.SilkS")
			(effects
				(font
					(size 0.7874 0.5842)
					(thickness 0.1524)
				)
				(justify mirror)
			)
		)
		(property "Value" "VAL*"
			(at -0.02032 2.13233 90)
			(unlocked yes)
			(layer "B.Fab")
			(hide yes)
			(effects
				(font
					(size 0.7874 0.5842)
					(thickness 0.1524)
				)
				(justify mirror)
			)
		)
		(property "Tolerance" "TOL*"
			(at -0.044704 3.05435 90)
			(unlocked yes)
			(layer "Cmts.User")
			(hide yes)
			(effects
				(font
					(size 0.7874 0.5842)
					(thickness 0.1524)
				)
				(justify mirror)
			)
		)
		(property "User Part Number" "PARTNUM*"
			(at -0.02032 4.024884 90)
			(unlocked yes)
			(layer "Cmts.User")
			(hide yes)
			(effects
				(font
					(size 0.7874 0.5842)
					(thickness 0.1524)
				)
				(justify mirror)
			)
		)
		(property "Device Type" "RESISTOR-G155-11001-01,1KOHM,1%"
			(at -0.008382 1.210564 90)
			(unlocked yes)
			(layer "B.Fab")
			(hide yes)
			(effects
				(font
					(size 0.7874 0.5842)
					(thickness 0.1524)
				)
				(justify mirror)
			)
		)
		(duplicate_pad_numbers_are_jumpers no)
		(fp_line
			(start 1.143 -0.5588)
			(end 1.143 0.5588)
			(stroke
				(width 0.1)
				(type default)
			)
			(layer "B.SilkS")
		)
		(fp_line
			(start -1.143 -0.5588)
			(end 1.143 -0.5588)
			(stroke
				(width 0.1)
				(type default)
			)
			(layer "B.SilkS")
		)
		(fp_line
			(start 1.143 0.5588)
			(end -1.143 0.5588)
			(stroke
				(width 0.1)
				(type default)
			)
			(layer "B.SilkS")
		)
		(fp_line
			(start -1.143 0.5588)
			(end -1.143 -0.5588)
			(stroke
				(width 0.1)
				(type default)
			)
			(layer "B.SilkS")
		)
		(fp_rect
			(start 1.143 0.5588)
			(end -1.143 -0.5588)
			(stroke
				(width 0)
				(type default)
			)
			(fill no)
			(layer "B.CrtYd")
		)
		(fp_line
			(start 0.508 -0.3048)
			(end 0.508 0.3048)
			(stroke
				(width 0.1)
				(type default)
			)
			(layer "B.Fab")
		)
		(fp_line
			(start -0.508 -0.3048)
			(end 0.508 -0.3048)
			(stroke
				(width 0.1)
				(type default)
			)
			(layer "B.Fab")
		)
		(fp_line
			(start 0.508 0.3048)
			(end -0.508 0.3048)
			(stroke
				(width 0.1)
				(type default)
			)
			(layer "B.Fab")
		)
		(fp_line
			(start -0.508 0.3048)
			(end -0.508 -0.3048)
			(stroke
				(width 0.1)
				(type default)
			)
			(layer "B.Fab")
		)
		(pad "1" smd rect
			(at 0.5334 0 270)
			(size 0.7112 0.6096)
			(layers "B.Cu" "B.Mask" "B.Paste")
			(net "XP5R0V_USB_CONN")
		)
		(pad "2" smd rect
			(at -0.5334 0 270)
			(size 0.7112 0.6096)
			(layers "B.Cu" "B.Mask" "B.Paste")
			(net "XP5R0V_USB_CONN_DET")
		)
		(zone
			(layer "B.Cu")
			(hatch none 0.5)
			(connect_pads
				(clearance 0)
			)
			(min_thickness 0.25)
			(keepout
				(tracks allowed)
				(vias not_allowed)
				(pads allowed)
				(copperpour not_allowed)
				(footprints allowed)
			)
			(placement
				(enabled no)
				(sheetname "")
			)
			(fill
				(thermal_gap 0.5)
				(thermal_bridge_width 0.5)
				(island_removal_mode 0)
			)
			(polygon
				(pts
					(xy 160.3248 -50.590196) (xy 159.7152 -50.590196) (xy 159.7152 -50.437796) (xy 160.3248 -50.437796)
				)
			)
		)
	)
	(footprint ""
		(layer "B.Cu")
		(at 53.975 -85.344)
		(property "Reference" "R444"
			(at 0.127 -5.92963 0)
			(unlocked yes)
			(layer "B.SilkS")
			(effects
				(font
					(size 0.7874 0.5842)
					(thickness 0.1524)
				)
				(justify mirror)
			)
		)
		(property "Value" "VAL*"
			(at -0.02032 2.13233 0)
			(unlocked yes)
			(layer "B.Fab")
			(hide yes)
			(effects
				(font
					(size 0.7874 0.5842)
					(thickness 0.1524)
				)
				(justify mirror)
			)
		)
		(property "Tolerance" "TOL*"
			(at -0.044704 3.05435 0)
			(unlocked yes)
			(layer "Cmts.User")
			(hide yes)
			(effects
				(font
					(size 0.7874 0.5842)
					(thickness 0.1524)
				)
				(justify mirror)
			)
		)
		(property "User Part Number" "PARTNUM*"
			(at -0.02032 4.024884 0)
			(unlocked yes)
			(layer "Cmts.User")
			(hide yes)
			(effects
				(font
					(size 0.7874 0.5842)
					(thickness 0.1524)
				)
				(justify mirror)
			)
		)
		(property "Device Type" "RESISTOR-G155-11002-01,10KOHM,A"
			(at -0.008382 1.210564 0)
			(unlocked yes)
			(layer "B.Fab")
			(hide yes)
			(effects
				(font
					(size 0.7874 0.5842)
					(thickness 0.1524)
				)
				(justify mirror)
			)
		)
		(duplicate_pad_numbers_are_jumpers no)
		(fp_line
			(start -1.143 -0.5588)
			(end 1.143 -0.5588)
			(stroke
				(width 0.1)
				(type default)
			)
			(layer "B.SilkS")
		)
		(fp_line
			(start -1.143 0.5588)
			(end -1.143 -0.5588)
			(stroke
				(width 0.1)
				(type default)
			)
			(layer "B.SilkS")
		)
		(fp_line
			(start 1.143 -0.5588)
			(end 1.143 0.5588)
			(stroke
				(width 0.1)
				(type default)
			)
			(layer "B.SilkS")
		)
		(fp_line
			(start 1.143 0.5588)
			(end -1.143 0.5588)
			(stroke
				(width 0.1)
				(type default)
			)
			(layer "B.SilkS")
		)
		(fp_poly
			(pts
				(xy 1.143 0.5588) (xy -1.143 0.5588) (xy -1.143 -0.5588) (xy 1.143 -0.5588)
			)
			(stroke
				(width 0)
				(type default)
			)
			(fill no)
			(layer "B.CrtYd")
		)
		(fp_line
			(start -0.508 -0.3048)
			(end 0.508 -0.3048)
			(stroke
				(width 0.1)
				(type default)
			)
			(layer "B.Fab")
		)
		(fp_line
			(start -0.508 0.3048)
			(end -0.508 -0.3048)
			(stroke
				(width 0.1)
				(type default)
			)
			(layer "B.Fab")
		)
		(fp_line
			(start 0.508 -0.3048)
			(end 0.508 0.3048)
			(stroke
				(width 0.1)
				(type default)
			)
			(layer "B.Fab")
		)
		(fp_line
			(start 0.508 0.3048)
			(end -0.508 0.3048)
			(stroke
				(width 0.1)
				(type default)
			)
			(layer "B.Fab")
		)
		(pad "1" smd rect
			(at 0.5334 0 180)
			(size 0.7112 0.6096)
			(layers "B.Cu" "B.Mask" "B.Paste")
			(net "XP3R3V_FT4232")
		)
		(pad "2" smd rect
			(at -0.5334 0 180)
			(size 0.7112 0.6096)
			(layers "B.Cu" "B.Mask" "B.Paste")
			(net "FTDI_EE_DO")
		)
		(zone
			(layer "B.Cu")
			(hatch none 0.5)
			(connect_pads
				(clearance 0)
			)
			(min_thickness 0.25)
			(keepout
				(tracks allowed)
				(vias not_allowed)
				(pads allowed)
				(copperpour not_allowed)
				(footprints allowed)
			)
			(placement
				(enabled no)
				(sheetname "")
			)
			(fill
				(thermal_gap 0.5)
				(thermal_bridge_width 0.5)
				(island_removal_mode 0)
			)
			(polygon
				(pts
					(xy 54.0512 -85.0392) (xy 54.0512 -85.6488) (xy 53.8988 -85.6488) (xy 53.8988 -85.0392)
				)
			)
		)
		(zone
			(layer "B.Cu")
			(hatch none 0.5)
			(connect_pads
				(clearance 0)
			)
			(min_thickness 0.25)
			(keepout
				(tracks not_allowed)
				(vias allowed)
				(pads allowed)
				(copperpour not_allowed)
				(footprints allowed)
			)
			(placement
				(enabled no)
				(sheetname "")
			)
			(fill
				(thermal_gap 0.5)
				(thermal_bridge_width 0.5)
				(island_removal_mode 0)
			)
			(polygon
				(pts
					(xy 54.0512 -85.0392) (xy 54.0512 -85.6488) (xy 53.8988 -85.6488) (xy 53.8988 -85.0392)
				)
			)
		)
	)
	(footprint ""
		(layer "B.Cu")
		(at 96.8756 -78.5368 180)
		(property "Reference" "R177"
			(at 0.3556 1.30683 0)
			(unlocked yes)
			(layer "B.SilkS")
			(effects
				(font
					(size 0.7874 0.5842)
					(thickness 0.1524)
				)
				(justify mirror)
			)
		)
		(property "Value" "VAL*"
			(at -0.0508 2.245106 180)
			(unlocked yes)
			(layer "B.Fab")
			(hide yes)
			(effects
				(font
					(size 0.7874 0.5842)
					(thickness 0.1524)
				)
				(justify mirror)
			)
		)
		(property "Tolerance" "TOL*"
			(at -0.0508 3.261106 180)
			(unlocked yes)
			(layer "Cmts.User")
			(hide yes)
			(effects
				(font
					(size 0.7874 0.5842)
					(thickness 0.1524)
				)
				(justify mirror)
			)
		)
		(property "Device Type" "RESISTOR-G152-00055-01,1.13KOHA"
			(at -0.0762 1.254506 180)
			(unlocked yes)
			(layer "B.Fab")
			(hide yes)
			(effects
				(font
					(size 0.7874 0.5842)
					(thickness 0.1524)
				)
				(justify mirror)
			)
		)
		(property "User Part Number" "PARTNUM*"
			(at -0.0762 4.302506 180)
			(unlocked yes)
			(layer "Cmts.User")
			(hide yes)
			(effects
				(font
					(size 0.7874 0.5842)
					(thickness 0.1524)
				)
				(justify mirror)
			)
		)
		(duplicate_pad_numbers_are_jumpers no)
		(fp_line
			(start 1.143 0.5588)
			(end -1.143 0.5588)
			(stroke
				(width 0.1)
				(type default)
			)
			(layer "B.SilkS")
		)
		(fp_line
			(start 1.143 -0.5588)
			(end 1.143 0.5588)
			(stroke
				(width 0.1)
				(type default)
			)
			(layer "B.SilkS")
		)
		(fp_line
			(start -1.143 0.5588)
			(end -1.143 -0.5588)
			(stroke
				(width 0.1)
				(type default)
			)
			(layer "B.SilkS")
		)
		(fp_line
			(start -1.143 -0.5588)
			(end 1.143 -0.5588)
			(stroke
				(width 0.1)
				(type default)
			)
			(layer "B.SilkS")
		)
		(fp_rect
			(start 1.143 0.5588)
			(end -1.143 -0.5588)
			(stroke
				(width 0)
				(type default)
			)
			(fill no)
			(layer "B.CrtYd")
		)
		(fp_line
			(start 0.508 0.3048)
			(end -0.508 0.3048)
			(stroke
				(width 0.1)
				(type default)
			)
			(layer "B.Fab")
		)
		(fp_line
			(start 0.508 -0.3048)
			(end 0.508 0.3048)
			(stroke
				(width 0.1)
				(type default)
			)
			(layer "B.Fab")
		)
		(fp_line
			(start -0.508 0.3048)
			(end -0.508 -0.3048)
			(stroke
				(width 0.1)
				(type default)
			)
			(layer "B.Fab")
		)
		(fp_line
			(start -0.508 -0.3048)
			(end 0.508 -0.3048)
			(stroke
				(width 0.1)
				(type default)
			)
			(layer "B.Fab")
		)
		(pad "1" smd rect
			(at 0.5334 0)
			(size 0.7112 0.6096)
			(layers "B.Cu" "B.Mask" "B.Paste")
			(net "XP1R2V_VIN")
		)
		(pad "2" smd rect
			(at -0.5334 0)
			(size 0.7112 0.6096)
			(layers "B.Cu" "B.Mask" "B.Paste")
			(net "XP1R2V_EN_R")
		)
		(zone
			(layer "B.Cu")
			(hatch none 0.5)
			(connect_pads
				(clearance 0)
			)
			(min_thickness 0.25)
			(keepout
				(tracks allowed)
				(vias not_allowed)
				(pads allowed)
				(copperpour not_allowed)
				(footprints allowed)
			)
			(placement
				(enabled no)
				(sheetname "")
			)
			(fill
				(thermal_gap 0.5)
				(thermal_bridge_width 0.5)
				(island_removal_mode 0)
			)
			(polygon
				(pts
					(xy 96.7994 -78.8416) (xy 96.7994 -78.232) (xy 96.9518 -78.232) (xy 96.9518 -78.8416)
				)
			)
		)
	)
)
